(kicad_pcb
	(version 20241229)
	(generator "pcbnew")
	(generator_version "9.0")
	(general
		(thickness 1.62)
		(legacy_teardrops no)
	)
	(paper "A3")
	(title_block
		(title "COM Express 7 Baseboard")
		(date "2025-02-04")
		(rev "1.1.2")
		(company "Antmicro Ltd")
		(comment 1 "www.antmicro.com")
		(comment 9 "footprints 186-188 of 802")
	)
	(layers
		(0 "F.Cu" signal)
		(4 "In1.Cu" signal)
		(6 "In2.Cu" signal)
		(8 "In3.Cu" signal)
		(10 "In4.Cu" signal)
		(12 "In5.Cu" signal)
		(14 "In6.Cu" signal)
		(2 "B.Cu" signal)
		(9 "F.Adhes" user "F.Adhesive")
		(11 "B.Adhes" user "B.Adhesive")
		(13 "F.Paste" user)
		(15 "B.Paste" user)
		(5 "F.SilkS" user "F.Silkscreen")
		(7 "B.SilkS" user "B.Silkscreen")
		(1 "F.Mask" user)
		(3 "B.Mask" user)
		(17 "Dwgs.User" user "User.Drawings")
		(19 "Cmts.User" user "User.Comments")
		(21 "Eco1.User" user "User.Eco1")
		(23 "Eco2.User" user "User.Eco2")
		(25 "Edge.Cuts" user)
		(27 "Margin" user)
		(31 "F.CrtYd" user "F.Courtyard")
		(29 "B.CrtYd" user "B.Courtyard")
		(35 "F.Fab" user)
		(33 "B.Fab" user)
	)
	(footprint "antmicro-footprints:C_0402_1005Metric"
		(layer "F.Cu")
		(at 314.114999 106.129999 -90)
		(descr "Capacitor SMD 0402")
		(tags "capacitor SMD 0402")
		(property "Reference" "C48"
			(at 1.730001 -1.735001 90)
			(layer "F.SilkS")
			(effects
				(font
					(size 0.7 0.7)
					(thickness 0.15)
				)
				(justify right bottom)
			)
		)
		(property "Value" "C_100n_0402"
			(at -1.022927 2.155213 90)
			(layer "F.Fab")
			(effects
				(font
					(size 0.7 0.7)
					(thickness 0.15)
				)
				(justify right bottom)
			)
		)
		(property "Datasheet" "https://www.murata.com/products/productdetail?partno=GRM155R61H104KE14%23"
			(at 0 0 270)
			(layer "F.Fab")
			(hide yes)
			(effects
				(font
					(size 1.27 1.27)
					(thickness 0.15)
				)
			)
		)
		(property "Author" "Antmicro"
			(at 207.985 420.244998 0)
			(layer "F.Fab")
			(hide yes)
			(effects
				(font
					(size 1 1)
					(thickness 0.15)
				)
			)
		)
		(property "Dielectric" "X5R"
			(at 207.985 420.244998 0)
			(layer "F.Fab")
			(hide yes)
			(effects
				(font
					(size 1 1)
					(thickness 0.15)
				)
			)
		)
		(property "License" "Apache-2.0"
			(at 207.985 420.244998 0)
			(layer "F.Fab")
			(hide yes)
			(effects
				(font
					(size 1 1)
					(thickness 0.15)
				)
			)
		)
		(property "MPN" "GRM155R61H104KE14D"
			(at 207.985 420.244998 0)
			(layer "F.Fab")
			(hide yes)
			(effects
				(font
					(size 1 1)
					(thickness 0.15)
				)
			)
		)
		(property "Manufacturer" "Murata"
			(at 207.985 420.244998 0)
			(layer "F.Fab")
			(hide yes)
			(effects
				(font
					(size 1 1)
					(thickness 0.15)
				)
			)
		)
		(property "Public" "False"
			(at 207.985 420.244998 0)
			(layer "F.Fab")
			(hide yes)
			(effects
				(font
					(size 1 1)
					(thickness 0.15)
				)
			)
		)
		(property "Val" "100n"
			(at 207.985 420.244998 0)
			(layer "F.Fab")
			(hide yes)
			(effects
				(font
					(size 1 1)
					(thickness 0.15)
				)
			)
		)
		(property "Voltage" "50V"
			(at 207.985 420.244998 0)
			(layer "F.Fab")
			(hide yes)
			(effects
				(font
					(size 1 1)
					(thickness 0.15)
				)
			)
		)
		(sheetname "Power")
		(sheetfile "power.kicad_sch")
		(attr smd)
		(fp_rect
			(start -0.925 -0.47)
			(end 0.925 0.47)
			(stroke
				(width 0.05)
				(type default)
			)
			(fill no)
			(layer "F.CrtYd")
		)
		(fp_line
			(start -0.494 0.248)
			(end -0.494 -0.25)
			(stroke
				(width 0.15)
				(type solid)
			)
			(layer "F.Fab")
		)
		(fp_line
			(start 0.504 0.248)
			(end -0.494 0.248)
			(stroke
				(width 0.15)
				(type solid)
			)
			(layer "F.Fab")
		)
		(fp_line
			(start -0.494 -0.25)
			(end 0.504 -0.25)
			(stroke
				(width 0.15)
				(type solid)
			)
			(layer "F.Fab")
		)
		(fp_line
			(start 0.504 -0.25)
			(end 0.504 0.248)
			(stroke
				(width 0.15)
				(type solid)
			)
			(layer "F.Fab")
		)
		(pad "1" smd roundrect
			(at -0.48 0 270)
			(size 0.59 0.64)
			(layers "F.Cu" "F.Mask" "F.Paste")
			(roundrect_rratio 0.25)
			(net 68 "Net-(U19-BST)")
			(pintype "passive")
			(teardrops
				(best_length_ratio 0.2)
				(max_length 1)
				(best_width_ratio 0.9)
				(max_width 2)
				(curved_edges yes)
				(filter_ratio 0.9)
				(enabled yes)
				(allow_two_segments yes)
				(prefer_zone_connections yes)
			)
		)
		(pad "2" smd roundrect
			(at 0.48 0 270)
			(size 0.59 0.64)
			(layers "F.Cu" "F.Mask" "F.Paste")
			(roundrect_rratio 0.25)
			(net 69 "Net-(C48-Pad2)")
			(pintype "passive")
			(teardrops
				(best_length_ratio 0.2)
				(max_length 1)
				(best_width_ratio 0.9)
				(max_width 2)
				(curved_edges yes)
				(filter_ratio 0.9)
				(enabled yes)
				(allow_two_segments yes)
				(prefer_zone_connections yes)
			)
		)
	)
	(footprint "antmicro-footprints:R_0402_1005Metric"
		(layer "F.Cu")
		(at 216.935 136.94 90)
		(descr "Resistor SMD 0402")
		(tags "resistor SMD 0402")
		(property "Reference" "R315"
			(at -3.72 0.465 90)
			(layer "F.SilkS")
			(effects
				(font
					(size 0.7 0.7)
					(thickness 0.15)
				)
				(justify left bottom)
			)
		)
		(property "Value" "R_0R_0402"
			(at -1.011843 1.772047 90)
			(layer "F.Fab")
			(effects
				(font
					(size 0.7 0.7)
					(thickness 0.15)
				)
				(justify left bottom)
			)
		)
		(property "Datasheet" "https://industrial.panasonic.com/cdbs/www-data/pdf/RDA0000/AOA0000C301.pdf"
			(at 0 0 90)
			(layer "F.Fab")
			(hide yes)
			(effects
				(font
					(size 1.27 1.27)
					(thickness 0.15)
				)
			)
		)
		(property "Author" "Antmicro"
			(at 353.875 -79.995 0)
			(layer "F.Fab")
			(hide yes)
			(effects
				(font
					(size 1 1)
					(thickness 0.15)
				)
			)
		)
		(property "Current" "1A"
			(at 353.875 -79.995 0)
			(layer "F.Fab")
			(hide yes)
			(effects
				(font
					(size 1 1)
					(thickness 0.15)
				)
			)
		)
		(property "License" "Apache-2.0"
			(at 353.875 -79.995 0)
			(layer "F.Fab")
			(hide yes)
			(effects
				(font
					(size 1 1)
					(thickness 0.15)
				)
			)
		)
		(property "MPN" "ERJ2GE0R00X"
			(at 353.875 -79.995 0)
			(layer "F.Fab")
			(hide yes)
			(effects
				(font
					(size 1 1)
					(thickness 0.15)
				)
			)
		)
		(property "Manufacturer" "Panasonic"
			(at 353.875 -79.995 0)
			(layer "F.Fab")
			(hide yes)
			(effects
				(font
					(size 1 1)
					(thickness 0.15)
				)
			)
		)
		(property "Public" "False"
			(at 353.875 -79.995 0)
			(layer "F.Fab")
			(hide yes)
			(effects
				(font
					(size 1 1)
					(thickness 0.15)
				)
			)
		)
		(property "Tolerance" ""
			(at 353.875 -79.995 0)
			(layer "F.Fab")
			(hide yes)
			(effects
				(font
					(size 1 1)
					(thickness 0.15)
				)
			)
		)
		(property "Val" "0R"
			(at 353.875 -79.995 0)
			(layer "F.Fab")
			(hide yes)
			(effects
				(font
					(size 1 1)
					(thickness 0.15)
				)
			)
		)
		(sheetname "PCIe misc")
		(sheetfile "pcie_misc.kicad_sch")
		(attr smd dnp)
		(fp_rect
			(start -0.925 -0.47)
			(end 0.925 0.47)
			(stroke
				(width 0.05)
				(type default)
			)
			(fill no)
			(layer "F.CrtYd")
		)
		(fp_rect
			(start -0.5 -0.25)
			(end 0.5 0.25)
			(stroke
				(width 0.15)
				(type solid)
			)
			(fill no)
			(layer "F.Fab")
		)
		(pad "1" smd roundrect
			(at -0.48 0 90)
			(size 0.59 0.64)
			(layers "F.Cu" "F.Mask" "F.Paste")
			(roundrect_rratio 0.25)
			(net 24 "/M.2 key E/~{CLKREQ}")
			(pintype "passive")
			(teardrops
				(best_length_ratio 0.2)
				(max_length 1)
				(best_width_ratio 0.9)
				(max_width 2)
				(curved_edges yes)
				(filter_ratio 0.9)
				(enabled yes)
				(allow_two_segments yes)
				(prefer_zone_connections yes)
			)
		)
		(pad "2" smd roundrect
			(at 0.48 0 90)
			(size 0.59 0.64)
			(layers "F.Cu" "F.Mask" "F.Paste")
			(roundrect_rratio 0.25)
			(net 604 "Net-(U37-~{OE2})")
			(pintype "passive")
			(teardrops
				(best_length_ratio 0.2)
				(max_length 1)
				(best_width_ratio 0.9)
				(max_width 2)
				(curved_edges yes)
				(filter_ratio 0.9)
				(enabled yes)
				(allow_two_segments yes)
				(prefer_zone_connections yes)
			)
		)
	)
	(footprint "antmicro-footprints:SOT-23-5"
		(layer "F.Cu")
		(at 303.19 130.09)
		(property "Reference" "U20"
			(at -1.09 2.72 0)
			(layer "F.SilkS")
			(effects
				(font
					(size 0.7 0.7)
					(thickness 0.15)
				)
				(justify left bottom)
			)
		)
		(property "Value" "TPS3840PL30DBVR"
			(at 0.002 2.799 0)
			(layer "F.Fab")
			(effects
				(font
					(size 0.7 0.7)
					(thickness 0.15)
				)
				(justify left bottom)
			)
		)
		(property "Datasheet" "https://www.ti.com/lit/ds/symlink/tps3840.pdf?HQS=dis-mous-null-mousermode-dsf-pf-null-wwe&DCM=yes&ref_url=https%3A%2F%2Fwww.mouser.com%2F&distId=26"
			(at 0 0 0)
			(layer "F.Fab")
			(hide yes)
			(effects
				(font
					(size 1.27 1.27)
					(thickness 0.15)
				)
			)
		)
		(property "Author" "Antmicro"
			(at 0 0 0)
			(layer "F.Fab")
			(hide yes)
			(effects
				(font
					(size 1 1)
					(thickness 0.15)
				)
			)
		)
		(property "License" "Apache-2.0"
			(at 0 0 0)
			(layer "F.Fab")
			(hide yes)
			(effects
				(font
					(size 1 1)
					(thickness 0.15)
				)
			)
		)
		(property "MPN" "TPS3840PL30DBVR"
			(at 0 0 0)
			(layer "F.Fab")
			(hide yes)
			(effects
				(font
					(size 1 1)
					(thickness 0.15)
				)
			)
		)
		(property "Manufacturer" "Texas Instruments"
			(at 0 0 0)
			(layer "F.Fab")
			(hide yes)
			(effects
				(font
					(size 1 1)
					(thickness 0.15)
				)
			)
		)
		(property ki_fp_filters "DBV0005A_N DBV0005A_M DBV0005A_L")
		(sheetname "Power")
		(sheetfile "power.kicad_sch")
		(attr smd)
		(fp_line
			(start -0.85 1.6)
			(end -0.85 1.301)
			(stroke
				(width 0.15)
				(type solid)
			)
			(layer "F.SilkS")
		)
		(fp_line
			(start -0.8 -1.6)
			(end -0.8 -1.3)
			(stroke
				(width 0.15)
				(type solid)
			)
			(layer "F.SilkS")
		)
		(fp_line
			(start -0.8 -1.6)
			(end -0.5 -1.6)
			(stroke
				(width 0.15)
				(type solid)
			)
			(layer "F.SilkS")
		)
		(fp_line
			(start -0.55 1.6)
			(end -0.85 1.6)
			(stroke
				(width 0.15)
				(type solid)
			)
			(layer "F.SilkS")
		)
		(fp_line
			(start 0.8 -1.6)
			(end 0.5 -1.6)
			(stroke
				(width 0.15)
				(type solid)
			)
			(layer "F.SilkS")
		)
		(fp_line
			(start 0.8 -1.3)
			(end 0.8 -1.6)
			(stroke
				(width 0.15)
				(type solid)
			)
			(layer "F.SilkS")
		)
		(fp_line
			(start 0.8 0.55)
			(end 0.8 -0.55)
			(stroke
				(width 0.15)
				(type solid)
			)
			(layer "F.SilkS")
		)
		(fp_line
			(start 0.8 1.3)
			(end 0.8 1.599)
			(stroke
				(width 0.15)
				(type solid)
			)
			(layer "F.SilkS")
		)
		(fp_line
			(start 0.8 1.599)
			(end 0.549 1.599)
			(stroke
				(width 0.15)
				(type solid)
			)
			(layer "F.SilkS")
		)
		(fp_circle
			(center -1.25 -1.5)
			(end -1.2 -1.5)
			(stroke
				(width 0.15)
				(type solid)
			)
			(fill yes)
			(layer "F.SilkS")
		)
		(fp_rect
			(start 1.9 -1.76)
			(end -1.9 1.75)
			(stroke
				(width 0.05)
				(type solid)
			)
			(fill no)
			(layer "F.CrtYd")
		)
		(fp_line
			(start -0.398 -1.526)
			(end -0.874 -1.05)
			(stroke
				(width 0.15)
				(type solid)
			)
			(layer "F.Fab")
		)
		(fp_rect
			(start 0.874 1.523)
			(end -0.873 -1.525)
			(stroke
				(width 0.15)
				(type solid)
			)
			(fill no)
			(layer "F.Fab")
		)
		(pad "1" smd rect
			(at -1.351 -0.951 270)
			(size 0.55 1)
			(layers "F.Cu" "F.Mask" "F.Paste")
			(net 365 "/Com Express 7 MGMT/PWR_OK")
			(pinfunction "~{RESET}")
			(pintype "output")
			(teardrops
				(best_length_ratio 0.2)
				(max_length 1)
				(best_width_ratio 0.9)
				(max_width 2)
				(curved_edges yes)
				(filter_ratio 0.9)
				(enabled yes)
				(allow_two_segments yes)
				(prefer_zone_connections yes)
			)
		)
		(pad "2" smd rect
			(at -1.351 0 270)
			(size 0.55 1)
			(layers "F.Cu" "F.Mask" "F.Paste")
			(net 73 "+3V3_AON")
			(pinfunction "VDD")
			(pintype "power_in")
			(teardrops
				(best_length_ratio 0.2)
				(max_length 1)
				(best_width_ratio 0.9)
				(max_width 2)
				(curved_edges yes)
				(filter_ratio 0.9)
				(enabled yes)
				(allow_two_segments yes)
				(prefer_zone_connections yes)
			)
		)
		(pad "3" smd rect
			(at -1.351 0.949 270)
			(size 0.55 1)
			(layers "F.Cu" "F.Mask" "F.Paste")
			(net 1 "GND")
			(pinfunction "GND")
			(pintype "power_in")
			(teardrops
				(best_length_ratio 0.2)
				(max_length 1)
				(best_width_ratio 0.9)
				(max_width 2)
				(curved_edges yes)
				(filter_ratio 0.9)
				(enabled yes)
				(allow_two_segments yes)
				(prefer_zone_connections yes)
			)
		)
		(pad "4" smd rect
			(at 1.35 0.949 270)
			(size 0.55 1)
			(layers "F.Cu" "F.Mask" "F.Paste")
			(net 582 "Net-(U20-~{MR})")
			(pinfunction "~{MR}")
			(pintype "input")
			(teardrops
				(best_length_ratio 0.2)
				(max_length 1)
				(best_width_ratio 0.9)
				(max_width 2)
				(curved_edges yes)
				(filter_ratio 0.9)
				(enabled yes)
				(allow_two_segments yes)
				(prefer_zone_connections yes)
			)
		)
		(pad "5" smd rect
			(at 1.35 -0.951 270)
			(size 0.55 1)
			(layers "F.Cu" "F.Mask" "F.Paste")
			(net 72 "Net-(U20-CT)")
			(pinfunction "CT")
			(pintype "passive")
			(teardrops
				(best_length_ratio 0.2)
				(max_length 1)
				(best_width_ratio 0.9)
				(max_width 2)
				(curved_edges yes)
				(filter_ratio 0.9)
				(enabled yes)
				(allow_two_segments yes)
				(prefer_zone_connections yes)
			)
		)
	)
)
